(kicad_pcb
	(version 20211014)
	(generator pcbnew)
	(general
    (thickness 1.6)
  )
	(paper "A4")
	(title_block
    (title "SA800U (Snapdragon 845) Baseboard")
    (date "2023-10-19")
    (rev "1.0.3")
    (company "Antmicro Ltd.")
    (comment 1 "www.antmicro.com")
		(comment 9 "footprint 58 of 589 (U11), pads 1-100 of 348")
	)
	(layers
    (0 "F.Cu" signal)
    (1 "In1.Cu" power)
    (2 "In2.Cu" signal)
    (3 "In3.Cu" signal)
    (4 "In4.Cu" power)
    (31 "B.Cu" signal)
    (32 "B.Adhes" user "B.Adhesive")
    (33 "F.Adhes" user "F.Adhesive")
    (34 "B.Paste" user)
    (35 "F.Paste" user)
    (36 "B.SilkS" user "B.Silkscreen")
    (37 "F.SilkS" user "F.Silkscreen")
    (38 "B.Mask" user)
    (39 "F.Mask" user)
    (40 "Dwgs.User" user "User.Drawings")
    (41 "Cmts.User" user "User.Comments")
    (42 "Eco1.User" user "User.Eco1")
    (43 "Eco2.User" user "User.Eco2")
    (44 "Edge.Cuts" user)
    (45 "Margin" user)
    (46 "B.CrtYd" user "B.Courtyard")
    (47 "F.CrtYd" user "F.Courtyard")
    (48 "B.Fab" user)
    (49 "F.Fab" user)
  )
	(footprint "sa800u-baseboard-hw-footprints:Receptacle_SA800U-WF" locked
    (layer "F.Cu")
    (tedit 6215E1EF)
    (at 112.47 100.96)
    (property "Author" "Antmicro")
    (property "License" "Apache-2.0")
    (property "MPN" "FX10A-168S-SV")
    (property "Manufacturer" "Hirose Electric")
    (property "Sheetfile" "som.kicad_sch")
    (property "Sheetname" "SoM")
    (attr smd)
    (fp_text reference "U11" (at 0.005 -19.31) (layer "F.SilkS")
      (effects (font (size 0.7 0.7) (thickness 0.15)) (justify left bottom))
    )
    (fp_text value "Receptacle_SA800U-WF" (at 0 20.4) (layer "F.Fab")
      (effects (font (size 0.7 0.7) (thickness 0.15)) (justify left bottom))
    )
    (pad "" np_thru_hole circle locked (at -26.538 -14.477) (size 4 4) (drill 2) (layers *.Cu *.Mask))
    (pad "" np_thru_hole circle locked (at 23.211 -14.477 270) (size 1.25 1.25) (drill 1.25) (layers *.Cu *.Mask))
    (pad "" np_thru_hole circle locked (at -28.538 14.524) (size 4 4) (drill 2) (layers *.Cu *.Mask))
    (pad "" np_thru_hole circle locked (at -21.189 -14.477 270) (size 1.25 1.25) (drill 1.25) (layers *.Mask "F.Cu"))
    (pad "" np_thru_hole circle locked (at 21.211 14.524 270) (size 1.25 1.25) (drill 1.25) (layers *.Cu *.Mask))
    (pad "" np_thru_hole circle locked (at 26.56 14.724) (size 4 4) (drill 2) (layers *.Cu *.Mask))
    (pad "" np_thru_hole circle locked (at -23.189 14.524 270) (size 1.25 1.25) (drill 1.25) (layers *.Cu *.Mask))
    (pad "" np_thru_hole circle locked (at 28.56 -14.477) (size 4 4) (drill 2) (layers *.Cu *.Mask))
    (pad "1_1" smd rect locked (at 21.76 -11.426 180) (size 0.33 1.6) (layers "F.Cu" "F.Paste" "F.Mask")
      (net 124 "PCIE0_RST_N") (pinfunction "PCIE0_RST_N") (pintype "output"))
    (pad "1_2" smd rect locked (at 21.76 -17.526 180) (size 0.33 1.6) (layers "F.Cu" "F.Paste" "F.Mask")
      (net 1 "GND") (pinfunction "GND") (pintype "passive"))
    (pad "1_3" smd rect locked (at 21.26 -11.426 180) (size 0.33 1.6) (layers "F.Cu" "F.Paste" "F.Mask")
      (net 119 "PCIE0_WAKE_N") (pinfunction "PCIE0_WAKE_N") (pintype "input"))
    (pad "1_4" smd rect locked (at 21.26 -17.526 180) (size 0.33 1.6) (layers "F.Cu" "F.Paste" "F.Mask")
      (net 28 "CSI0_LN3_P") (pinfunction "CSI0_LN3_P") (pintype "input"))
    (pad "1_5" smd rect locked (at 20.76 -11.426 180) (size 0.33 1.6) (layers "F.Cu" "F.Paste" "F.Mask")
      (net 120 "PCIE0_CLKREQ_N") (pinfunction "PCIE0_CLKREQ_N") (pintype "input"))
    (pad "1_6" smd rect locked (at 20.76 -17.526 180) (size 0.33 1.6) (layers "F.Cu" "F.Paste" "F.Mask")
      (net 27 "CSI0_LN3_N") (pinfunction "CSI0_LN3_N") (pintype "input"))
    (pad "1_7" smd rect locked (at 20.26 -11.426 180) (size 0.33 1.6) (layers "F.Cu" "F.Paste" "F.Mask")
      (net 1 "GND") (pinfunction "GND") (pintype "passive"))
    (pad "1_8" smd rect locked (at 20.26 -17.526 180) (size 0.33 1.6) (layers "F.Cu" "F.Paste" "F.Mask")
      (net 1 "GND") (pinfunction "GND") (pintype "passive"))
    (pad "1_9" smd rect locked (at 19.76 -11.426 180) (size 0.33 1.6) (layers "F.Cu" "F.Paste" "F.Mask")
      (net 110 "PCIE0_TX_N") (pinfunction "PCIE0_TX_M") (pintype "output"))
    (pad "1_10" smd rect locked (at 19.76 -17.526 180) (size 0.33 1.6) (layers "F.Cu" "F.Paste" "F.Mask")
      (net 30 "CSI0_LN2_N") (pinfunction "CSI0_LN2_N") (pintype "input"))
    (pad "1_11" smd rect locked (at 19.26 -11.426 180) (size 0.33 1.6) (layers "F.Cu" "F.Paste" "F.Mask")
      (net 108 "PCIE0_TX_P") (pinfunction "PCIE0_TX_P") (pintype "output"))
    (pad "1_12" smd rect locked (at 19.26 -17.526 180) (size 0.33 1.6) (layers "F.Cu" "F.Paste" "F.Mask")
      (net 29 "CSI0_LN2_P") (pinfunction "CSI0_LN2_P") (pintype "input"))
    (pad "1_13" smd rect locked (at 18.76 -11.426 180) (size 0.33 1.6) (layers "F.Cu" "F.Paste" "F.Mask")
      (net 1 "GND") (pinfunction "GND") (pintype "passive"))
    (pad "1_14" smd rect locked (at 18.76 -17.526 180) (size 0.33 1.6) (layers "F.Cu" "F.Paste" "F.Mask")
      (net 1 "GND") (pinfunction "GND") (pintype "passive"))
    (pad "1_15" smd rect locked (at 18.26 -11.426 180) (size 0.33 1.6) (layers "F.Cu" "F.Paste" "F.Mask")
      (net 122 "PCIE0_REFCLK_P") (pinfunction "PCIE0_REFCLK_P") (pintype "output"))
    (pad "1_16" smd rect locked (at 18.26 -17.526 180) (size 0.33 1.6) (layers "F.Cu" "F.Paste" "F.Mask")
      (net 31 "CSI0_LN1_N") (pinfunction "CSI0_LN1_N") (pintype "input"))
    (pad "1_17" smd rect locked (at 17.76 -11.426 180) (size 0.33 1.6) (layers "F.Cu" "F.Paste" "F.Mask")
      (net 126 "PCIE0_REFCLK_N") (pinfunction "PCIE0_REFCLK_M") (pintype "output"))
    (pad "1_18" smd rect locked (at 17.76 -17.526 180) (size 0.33 1.6) (layers "F.Cu" "F.Paste" "F.Mask")
      (net 32 "CSI0_LN1_P") (pinfunction "CSI0_LN1_P") (pintype "input"))
    (pad "1_19" smd rect locked (at 17.26 -11.426 180) (size 0.33 1.6) (layers "F.Cu" "F.Paste" "F.Mask")
      (net 1 "GND") (pinfunction "GND") (pintype "passive"))
    (pad "1_20" smd rect locked (at 17.26 -17.526 180) (size 0.33 1.6) (layers "F.Cu" "F.Paste" "F.Mask")
      (net 1 "GND") (pinfunction "GND") (pintype "passive"))
    (pad "1_21" smd rect locked (at 16.76 -11.426 180) (size 0.33 1.6) (layers "F.Cu" "F.Paste" "F.Mask")
      (net 123 "PCIE0_RX_P") (pinfunction "PCIE0_RX_P") (pintype "input"))
    (pad "1_22" smd rect locked (at 16.76 -17.526 180) (size 0.33 1.6) (layers "F.Cu" "F.Paste" "F.Mask")
      (net 33 "CSI0_LN0_N") (pinfunction "CSI0_LN0_N") (pintype "input"))
    (pad "1_23" smd rect locked (at 16.26 -11.426 180) (size 0.33 1.6) (layers "F.Cu" "F.Paste" "F.Mask")
      (net 125 "PCIE0_RX_N") (pinfunction "PCIE0_RX_M") (pintype "input"))
    (pad "1_24" smd rect locked (at 16.26 -17.526 180) (size 0.33 1.6) (layers "F.Cu" "F.Paste" "F.Mask")
      (net 34 "CSI0_LN0_P") (pinfunction "CSI0_LN0_P") (pintype "input"))
    (pad "1_25" smd rect locked (at 15.761 -11.426 180) (size 0.33 1.6) (layers "F.Cu" "F.Paste" "F.Mask")
      (net 1 "GND") (pinfunction "GND") (pintype "passive"))
    (pad "1_26" smd rect locked (at 15.761 -17.526 180) (size 0.33 1.6) (layers "F.Cu" "F.Paste" "F.Mask")
      (net 1 "GND") (pinfunction "GND") (pintype "passive"))
    (pad "1_27" smd rect locked (at 15.261 -11.426 180) (size 0.33 1.6) (layers "F.Cu" "F.Paste" "F.Mask")
      (net 625 "unconnected-(U11-Pad1_27)") (pinfunction "UFS_RX_M") (pintype "input+no_connect"))
    (pad "1_28" smd rect locked (at 15.261 -17.526 180) (size 0.33 1.6) (layers "F.Cu" "F.Paste" "F.Mask")
      (net 13 "CSI0_CLK_P") (pinfunction "CSI0_CLK_P") (pintype "input"))
    (pad "1_29" smd rect locked (at 14.761 -11.426 180) (size 0.33 1.6) (layers "F.Cu" "F.Paste" "F.Mask")
      (net 624 "unconnected-(U11-Pad1_29)") (pinfunction "UFS_RX_P") (pintype "input+no_connect"))
    (pad "1_30" smd rect locked (at 14.761 -17.526 180) (size 0.33 1.6) (layers "F.Cu" "F.Paste" "F.Mask")
      (net 12 "CSI0_CLK_N") (pinfunction "CSI0_CLK_N") (pintype "input"))
    (pad "1_31" smd rect locked (at 14.261 -11.426 180) (size 0.33 1.6) (layers "F.Cu" "F.Paste" "F.Mask")
      (net 1 "GND") (pinfunction "GND") (pintype "passive"))
    (pad "1_32" smd rect locked (at 14.261 -17.526 180) (size 0.33 1.6) (layers "F.Cu" "F.Paste" "F.Mask")
      (net 1 "GND") (pinfunction "GND") (pintype "passive"))
    (pad "1_33" smd rect locked (at 13.761 -11.426 180) (size 0.33 1.6) (layers "F.Cu" "F.Paste" "F.Mask")
      (net 623 "unconnected-(U11-Pad1_33)") (pinfunction "UFS_TX_P") (pintype "output+no_connect"))
    (pad "1_34" smd rect locked (at 13.761 -17.526 180) (size 0.33 1.6) (layers "F.Cu" "F.Paste" "F.Mask")
      (net 18 "CSI1_LN3_N") (pinfunction "CSI1_LN3_N") (pintype "input"))
    (pad "1_35" smd rect locked (at 13.261 -11.426 180) (size 0.33 1.6) (layers "F.Cu" "F.Paste" "F.Mask")
      (net 622 "unconnected-(U11-Pad1_35)") (pinfunction "UFS_TX_M") (pintype "output+no_connect"))
    (pad "1_36" smd rect locked (at 13.261 -17.526 180) (size 0.33 1.6) (layers "F.Cu" "F.Paste" "F.Mask")
      (net 17 "CSI1_LN3_P") (pinfunction "CSI1_LN3_P") (pintype "input"))
    (pad "1_37" smd rect locked (at 12.761 -11.426 180) (size 0.33 1.6) (layers "F.Cu" "F.Paste" "F.Mask")
      (net 1 "GND") (pinfunction "GND") (pintype "passive"))
    (pad "1_38" smd rect locked (at 12.761 -17.526 180) (size 0.33 1.6) (layers "F.Cu" "F.Paste" "F.Mask")
      (net 1 "GND") (pinfunction "GND") (pintype "passive"))
    (pad "1_39" smd rect locked (at 12.261 -11.426 180) (size 0.33 1.6) (layers "F.Cu" "F.Paste" "F.Mask")
      (net 621 "unconnected-(U11-Pad1_39)") (pinfunction "UFS_CLK") (pintype "output+no_connect"))
    (pad "1_40" smd rect locked (at 12.261 -17.526 180) (size 0.33 1.6) (layers "F.Cu" "F.Paste" "F.Mask")
      (net 19 "CSI1_LN2_P") (pinfunction "CSI1_LN2_P") (pintype "input"))
    (pad "1_41" smd rect locked (at 11.761 -11.426 180) (size 0.33 1.6) (layers "F.Cu" "F.Paste" "F.Mask")
      (net 1 "GND") (pinfunction "GND") (pintype "passive"))
    (pad "1_42" smd rect locked (at 11.761 -17.526 180) (size 0.33 1.6) (layers "F.Cu" "F.Paste" "F.Mask")
      (net 20 "CSI1_LN2_N") (pinfunction "CSI1_LN2_N") (pintype "input"))
    (pad "1_43" smd rect locked (at 11.261 -11.426 180) (size 0.33 1.6) (layers "F.Cu" "F.Paste" "F.Mask")
      (net 620 "/SoM/LCM_VDD_EN") (pinfunction "UFS_DET") (pintype "output+no_connect"))
    (pad "1_44" smd rect locked (at 11.261 -17.526 180) (size 0.33 1.6) (layers "F.Cu" "F.Paste" "F.Mask")
      (net 1 "GND") (pinfunction "GND") (pintype "passive"))
    (pad "1_45" smd rect locked (at 10.761 -11.426 180) (size 0.33 1.6) (layers "F.Cu" "F.Paste" "F.Mask")
      (net 116 "SD_CLK") (pinfunction "SD_CLK") (pintype "output"))
    (pad "1_46" smd rect locked (at 10.761 -17.526 180) (size 0.33 1.6) (layers "F.Cu" "F.Paste" "F.Mask")
      (net 22 "CSI1_LN1_N") (pinfunction "CSI1_LN1_N") (pintype "input"))
    (pad "1_47" smd rect locked (at 10.261 -11.426 180) (size 0.33 1.6) (layers "F.Cu" "F.Paste" "F.Mask")
      (net 115 "SD_CMD") (pinfunction "SD_CMD") (pintype "output"))
    (pad "1_48" smd rect locked (at 10.261 -17.526 180) (size 0.33 1.6) (layers "F.Cu" "F.Paste" "F.Mask")
      (net 21 "CSI1_LN1_P") (pinfunction "CSI1_LN1_P") (pintype "input"))
    (pad "1_49" smd rect locked (at 9.761 -11.426 180) (size 0.33 1.6) (layers "F.Cu" "F.Paste" "F.Mask")
      (net 112 "SD_DET") (pinfunction "SD_DET") (pintype "input"))
    (pad "1_50" smd rect locked (at 9.761 -17.526 180) (size 0.33 1.6) (layers "F.Cu" "F.Paste" "F.Mask")
      (net 1 "GND") (pinfunction "GND") (pintype "passive"))
    (pad "1_51" smd rect locked (at 9.261 -11.426 180) (size 0.33 1.6) (layers "F.Cu" "F.Paste" "F.Mask")
      (net 118 "SD_DATA0") (pinfunction "SD_DATA0") (pintype "bidirectional"))
    (pad "1_52" smd rect locked (at 9.261 -17.526 180) (size 0.33 1.6) (layers "F.Cu" "F.Paste" "F.Mask")
      (net 23 "CSI1_LN0_N") (pinfunction "CSI1_LN0_N") (pintype "input"))
    (pad "1_53" smd rect locked (at 8.761 -11.426 180) (size 0.33 1.6) (layers "F.Cu" "F.Paste" "F.Mask")
      (net 117 "SD_DATA1") (pinfunction "SD_DATA1") (pintype "bidirectional"))
    (pad "1_54" smd rect locked (at 8.761 -17.526 180) (size 0.33 1.6) (layers "F.Cu" "F.Paste" "F.Mask")
      (net 24 "CSI1_LN0_P") (pinfunction "CSI1_LN0_P") (pintype "input"))
    (pad "1_55" smd rect locked (at 8.261 -11.426 180) (size 0.33 1.6) (layers "F.Cu" "F.Paste" "F.Mask")
      (net 113 "SD_DATA3") (pinfunction "SD_DATA3") (pintype "bidirectional"))
    (pad "1_56" smd rect locked (at 8.261 -17.526 180) (size 0.33 1.6) (layers "F.Cu" "F.Paste" "F.Mask")
      (net 1 "GND") (pinfunction "GND") (pintype "passive"))
    (pad "1_57" smd rect locked (at 7.76 -11.426 180) (size 0.33 1.6) (layers "F.Cu" "F.Paste" "F.Mask")
      (net 114 "SD_DATA2") (pinfunction "SD_DATA2") (pintype "bidirectional"))
    (pad "1_58" smd rect locked (at 7.76 -17.526 180) (size 0.33 1.6) (layers "F.Cu" "F.Paste" "F.Mask")
      (net 26 "CSI1_CLK_N") (pinfunction "CSI1_CLK_N") (pintype "input"))
    (pad "1_59" smd rect locked (at 7.26 -11.426 180) (size 0.33 1.6) (layers "F.Cu" "F.Paste" "F.Mask")
      (net 1 "GND") (pinfunction "GND") (pintype "passive"))
    (pad "1_60" smd rect locked (at 7.26 -17.526 180) (size 0.33 1.6) (layers "F.Cu" "F.Paste" "F.Mask")
      (net 25 "CSI1_CLK_P") (pinfunction "CSI1_CLK_P") (pintype "input"))
    (pad "1_61" smd rect locked (at 6.76 -11.426 180) (size 0.33 1.6) (layers "F.Cu" "F.Paste" "F.Mask")
      (net 619 "/SoM/CSI2_CLK_P") (pinfunction "CSI2_CLK_P") (pintype "input+no_connect"))
    (pad "1_62" smd rect locked (at 6.76 -17.526 180) (size 0.33 1.6) (layers "F.Cu" "F.Paste" "F.Mask")
      (net 1 "GND") (pinfunction "GND") (pintype "passive"))
    (pad "1_63" smd rect locked (at 6.26 -11.426 180) (size 0.33 1.6) (layers "F.Cu" "F.Paste" "F.Mask")
      (net 618 "/SoM/CSI2_CLK_N") (pinfunction "CSI2_CLK_N") (pintype "input+no_connect"))
    (pad "1_64" smd rect locked (at 6.26 -17.526 180) (size 0.33 1.6) (layers "F.Cu" "F.Paste" "F.Mask")
      (net 617 "/SoM/CSI2_LN1_P") (pinfunction "CSI2_LN1_P") (pintype "input+no_connect"))
    (pad "1_65" smd rect locked (at 5.761 -11.426 180) (size 0.33 1.6) (layers "F.Cu" "F.Paste" "F.Mask")
      (net 1 "GND") (pinfunction "GND") (pintype "passive"))
    (pad "1_66" smd rect locked (at 5.761 -17.526 180) (size 0.33 1.6) (layers "F.Cu" "F.Paste" "F.Mask")
      (net 616 "/SoM/CSI2_LN1_N") (pinfunction "CSI2_LN1_N") (pintype "input+no_connect"))
    (pad "1_67" smd rect locked (at 5.261 -11.426 180) (size 0.33 1.6) (layers "F.Cu" "F.Paste" "F.Mask")
      (net 615 "/SoM/CSI2_LN0_N") (pinfunction "CSI2_LN0_N") (pintype "input+no_connect"))
    (pad "1_68" smd rect locked (at 5.261 -17.526 180) (size 0.33 1.6) (layers "F.Cu" "F.Paste" "F.Mask")
      (net 1 "GND") (pinfunction "GND") (pintype "passive"))
    (pad "1_69" smd rect locked (at 4.761 -11.426 180) (size 0.33 1.6) (layers "F.Cu" "F.Paste" "F.Mask")
      (net 614 "/SoM/CSI2_LN0_P") (pinfunction "CSI2_LN0_P") (pintype "input+no_connect"))
    (pad "1_70" smd rect locked (at 4.761 -17.526 180) (size 0.33 1.6) (layers "F.Cu" "F.Paste" "F.Mask")
      (net 613 "/SoM/CSI2_LN2_P") (pinfunction "CSI2_LN2_P") (pintype "input+no_connect"))
    (pad "1_71" smd rect locked (at 4.261 -11.426 180) (size 0.33 1.6) (layers "F.Cu" "F.Paste" "F.Mask")
      (net 1 "GND") (pinfunction "GND") (pintype "passive"))
    (pad "1_72" smd rect locked (at 4.261 -17.526 180) (size 0.33 1.6) (layers "F.Cu" "F.Paste" "F.Mask")
      (net 612 "/SoM/CSI2_LN2_N") (pinfunction "CSI2_LN2_N") (pintype "input+no_connect"))
    (pad "1_73" smd rect locked (at 3.761 -11.426 180) (size 0.33 1.6) (layers "F.Cu" "F.Paste" "F.Mask")
      (net 611 "/SoM/CSI3_LN1_N") (pinfunction "CSI3_LN1_N") (pintype "input+no_connect"))
    (pad "1_74" smd rect locked (at 3.761 -17.526 180) (size 0.33 1.6) (layers "F.Cu" "F.Paste" "F.Mask")
      (net 1 "GND") (pinfunction "GND") (pintype "passive"))
    (pad "1_75" smd rect locked (at 3.261 -11.426 180) (size 0.33 1.6) (layers "F.Cu" "F.Paste" "F.Mask")
      (net 610 "/SoM/CSI3_LN1_P") (pinfunction "CSI3_LN1_P") (pintype "input+no_connect"))
    (pad "1_76" smd rect locked (at 3.261 -17.526 180) (size 0.33 1.6) (layers "F.Cu" "F.Paste" "F.Mask")
      (net 609 "/SoM/CSI2_LN3_P") (pinfunction "CSI2_LN3_P") (pintype "input+no_connect"))
    (pad "1_77" smd rect locked (at 2.761 -11.426 180) (size 0.33 1.6) (layers "F.Cu" "F.Paste" "F.Mask")
      (net 1 "GND") (pinfunction "GND") (pintype "passive"))
    (pad "1_78" smd rect locked (at 2.761 -17.526 180) (size 0.33 1.6) (layers "F.Cu" "F.Paste" "F.Mask")
      (net 608 "/SoM/CSI2_LN3_N") (pinfunction "CSI2_LN3_N") (pintype "input+no_connect"))
    (pad "1_79" smd rect locked (at 2.261 -11.426 180) (size 0.33 1.6) (layers "F.Cu" "F.Paste" "F.Mask")
      (net 607 "/SoM/CSI3_LN0_P") (pinfunction "CSI3_LN0_P") (pintype "input+no_connect"))
    (pad "1_80" smd rect locked (at 2.261 -17.526 180) (size 0.33 1.6) (layers "F.Cu" "F.Paste" "F.Mask")
      (net 1 "GND") (pinfunction "GND") (pintype "passive"))
    (pad "1_81" smd rect locked (at 1.761 -11.426 180) (size 0.33 1.6) (layers "F.Cu" "F.Paste" "F.Mask")
      (net 606 "/SoM/CSI3_LN0_N") (pinfunction "CSI3_LN0_N") (pintype "input+no_connect"))
    (pad "1_82" smd rect locked (at 1.761 -17.526 180) (size 0.33 1.6) (layers "F.Cu" "F.Paste" "F.Mask")
      (net 605 "unconnected-(U11-Pad1_82)") (pinfunction "SDC4_DATA0") (pintype "output+no_connect"))
    (pad "1_83" smd rect locked (at 1.261 -11.426 180) (size 0.33 1.6) (layers "F.Cu" "F.Paste" "F.Mask")
      (net 1 "GND") (pinfunction "GND") (pintype "passive"))
    (pad "1_84" smd rect locked (at 1.261 -17.526 180) (size 0.33 1.6) (layers "F.Cu" "F.Paste" "F.Mask")
      (net 604 "unconnected-(U11-Pad1_84)") (pinfunction "SDC4_DATA1") (pintype "output+no_connect"))
    (pad "1_85" smd rect locked (at 0.76 -11.426 180) (size 0.33 1.6) (layers "F.Cu" "F.Paste" "F.Mask")
      (net 603 "/SoM/CSI3_CLK_N") (pinfunction "CSI3_CLK_N") (pintype "input+no_connect"))
    (pad "1_86" smd rect locked (at 0.76 -17.526 180) (size 0.33 1.6) (layers "F.Cu" "F.Paste" "F.Mask")
      (net 602 "/SoM/CAM0_AFVDD_EN") (pinfunction "SDC4_CLK") (pintype "output+no_connect"))
    (pad "1_87" smd rect locked (at 0.261 -11.426 180) (size 0.33 1.6) (layers "F.Cu" "F.Paste" "F.Mask")
      (net 601 "/SoM/CSI3_CLK_P") (pinfunction "CSI3_CLK_P") (pintype "input+no_connect"))
    (pad "1_88" smd rect locked (at 0.261 -17.526 180) (size 0.33 1.6) (layers "F.Cu" "F.Paste" "F.Mask")
      (net 600 "/SoM/CAM1_AFVDD_EN") (pinfunction "SDC4_DATA2") (pintype "output+no_connect"))
    (pad "1_89" smd rect locked (at -0.24 -11.426 180) (size 0.33 1.6) (layers "F.Cu" "F.Paste" "F.Mask")
      (net 1 "GND") (pinfunction "GND") (pintype "passive"))
    (pad "1_90" smd rect locked (at -0.24 -17.526 180) (size 0.33 1.6) (layers "F.Cu" "F.Paste" "F.Mask")
      (net 599 "/SoM/LT6911_RST") (pinfunction "SDC4_DATA3") (pintype "output+no_connect"))
    (pad "1_91" smd rect locked (at -0.739 -11.426 180) (size 0.33 1.6) (layers "F.Cu" "F.Paste" "F.Mask")
      (net 598 "/SoM/CAM0_MCLK") (pinfunction "CAM0_MCLK") (pintype "output+no_connect"))
    (pad "1_92" smd rect locked (at -0.739 -17.526 180) (size 0.33 1.6) (layers "F.Cu" "F.Paste" "F.Mask")
      (net 597 "/SoM/HDMI1_INTO") (pinfunction "SDC4_CMD") (pintype "output+no_connect"))
  )
)
